# BASEBOARD_FAB2 (Tioga Pass) — schematic netlist excerpt (pin names and nets, part order shuffled) for the footprints in the layout excerpt that follows; sources: Cadence DE-HDL packaged netlist, KiCad conversion of Wiwynn_Tioga_Pass_MB.brd

R1R8  RES  0.0 5% CHIP  pkg 0402  page 170 : A = FM_THROTTLE_R1_N ; B = FM_THROTTLE_N
C2R15  CAP_A  0.1UF 16V 10% X7R  pkg 0402V  page 188 : A = P12V_STBY ; B = GND
C5L15  CAP_A  47UF 4V 20% X5R  pkg 0603V  page 220 : A = PVDDQ_DEF ; B = GND

(kicad_pcb
	(version 20260206)
	(generator "pcbnew")
	(generator_version "10.0")
	(general
		(thickness 1.6)
		(legacy_teardrops no)
	)
	(paper "A4")
	(title_block
		(title "Wiwynn_Tioga_Pass_MB.brd")
		(comment 1 "Tioga Pass / footprints 4019-4021 of 4770")
	)
	(layers
		(0 "F.Cu" signal "TOP")
		(4 "In1.Cu" signal "L2GND")
		(6 "In2.Cu" signal "L3")
		(8 "In3.Cu" signal "L4GND")
		(10 "In4.Cu" signal "L5")
		(12 "In5.Cu" signal "L6GND")
		(14 "In6.Cu" signal "L7VCC")
		(16 "In7.Cu" signal "L8VCC")
		(18 "In8.Cu" signal "L9GND")
		(20 "In9.Cu" signal "L10")
		(22 "In10.Cu" signal "L11GND")
		(24 "In11.Cu" signal "L12")
		(26 "In12.Cu" signal "L13GND")
		(2 "B.Cu" signal "BOTTOM")
		(9 "F.Adhes" user "F.Adhesive")
		(11 "B.Adhes" user "B.Adhesive")
		(13 "F.Paste" user "Package Geometry/Pastemask Top")
		(15 "B.Paste" user "Package Geometry/Pastemask Bottom")
		(5 "F.SilkS" user "Ref Des/Silkscreen Top")
		(7 "B.SilkS" user "Ref Des/Silkscreen Bottom")
		(1 "F.Mask" user "Board Geometry/Soldermask Top")
		(3 "B.Mask" user "Board Geometry/Soldermask Bottom")
		(17 "Dwgs.User" user "User.Drawings")
		(19 "Cmts.User" user "User.Comments")
		(21 "Eco1.User" user "User.Eco1")
		(23 "Eco2.User" user "User.Eco2")
		(25 "Edge.Cuts" user "Board Geometry/Outline")
		(27 "Margin" user)
		(31 "F.CrtYd" user "Package Geometry/Place Bound Top")
		(29 "B.CrtYd" user "Package Geometry/Place Bound Bottom")
		(35 "F.Fab" user "Ref Des/Assembly Top")
		(33 "B.Fab" user "Ref Des/Assembly Bottom")
	)
	(footprint ""
		(layer "B.Cu")
		(at 258.2037 -144.8816 -90)
		(property "Reference" "C5L15"
			(at 0 0 90)
			(layer "B.SilkS")
			(hide yes)
			(effects
				(font
					(size 1.27 1.27)
				)
				(justify mirror)
			)
		)
		(property "Value" ""
			(at 0 0 90)
			(layer "B.Fab")
			(effects
				(font
					(size 1.27 1.27)
				)
				(justify mirror)
			)
		)
		(duplicate_pad_numbers_are_jumpers no)
		(fp_rect
			(start 0.500126 1.598422)
			(end -0.500126 -0.201422)
			(stroke
				(width 0)
				(type default)
			)
			(fill no)
			(layer "B.CrtYd")
		)
		(fp_line
			(start -0.500126 1.598422)
			(end 0.500126 1.598422)
			(stroke
				(width 0.1)
				(type default)
			)
			(layer "B.Fab")
		)
		(fp_line
			(start 0.500126 1.598422)
			(end 0.500126 -0.201422)
			(stroke
				(width 0.1)
				(type default)
			)
			(layer "B.Fab")
		)
		(fp_line
			(start -0.500126 -0.201422)
			(end -0.500126 1.598422)
			(stroke
				(width 0.1)
				(type default)
			)
			(layer "B.Fab")
		)
		(fp_line
			(start 0.500126 -0.201422)
			(end -0.500126 -0.201422)
			(stroke
				(width 0.1)
				(type default)
			)
			(layer "B.Fab")
		)
		(pad "1" smd rect
			(at 0 0 180)
			(size 0.889 0.9906)
			(layers "B.Cu" "B.Mask" "B.Paste")
			(net "PVDDQ_DEF")
		)
		(pad "2" smd rect
			(at 0 1.397 180)
			(size 0.889 0.9906)
			(layers "B.Cu" "B.Mask" "B.Paste")
			(net "GND")
		)
		(zone
			(layer "B.Cu")
			(hatch none 0.5)
			(connect_pads
				(clearance 0)
			)
			(min_thickness 0.25)
			(keepout
				(tracks allowed)
				(vias not_allowed)
				(pads allowed)
				(copperpour not_allowed)
				(footprints allowed)
			)
			(placement
				(enabled no)
				(sheetname "")
			)
			(fill
				(thermal_gap 0.5)
				(thermal_bridge_width 0.5)
				(island_removal_mode 0)
			)
			(polygon
				(pts
					(xy 257.2512 -144.3863) (xy 257.7592 -144.3863) (xy 257.7592 -145.3769) (xy 257.2512 -145.3769)
				)
			)
		)
		(zone
			(layer "B.Cu")
			(hatch none 0.5)
			(connect_pads
				(clearance 0)
			)
			(min_thickness 0.25)
			(keepout
				(tracks not_allowed)
				(vias allowed)
				(pads allowed)
				(copperpour not_allowed)
				(footprints allowed)
			)
			(placement
				(enabled no)
				(sheetname "")
			)
			(fill
				(thermal_gap 0.5)
				(thermal_bridge_width 0.5)
				(island_removal_mode 0)
			)
			(polygon
				(pts
					(xy 257.2512 -144.3863) (xy 257.7592 -144.3863) (xy 257.7592 -145.3769) (xy 257.2512 -145.3769)
				)
			)
		)
	)
	(footprint ""
		(layer "B.Cu")
		(at 439.293 -52.3875)
		(property "Reference" "C2R15"
			(at 0 0 0)
			(layer "B.SilkS")
			(hide yes)
			(effects
				(font
					(size 1.27 1.27)
				)
				(justify mirror)
			)
		)
		(property "Value" ""
			(at 0 0 0)
			(layer "B.Fab")
			(effects
				(font
					(size 1.27 1.27)
				)
				(justify mirror)
			)
		)
		(duplicate_pad_numbers_are_jumpers no)
		(fp_poly
			(pts
				(xy -0.3048 -0.1016) (xy -0.3048 0.9906) (xy 0.3048 0.9906) (xy 0.3048 -0.1016)
			)
			(stroke
				(width 0)
				(type default)
			)
			(fill no)
			(layer "B.CrtYd")
		)
		(fp_line
			(start -0.3048 -0.1016)
			(end 0.3048 -0.1016)
			(stroke
				(width 0.1)
				(type default)
			)
			(layer "B.Fab")
		)
		(fp_line
			(start -0.3048 0.9906)
			(end -0.3048 -0.1016)
			(stroke
				(width 0.1)
				(type default)
			)
			(layer "B.Fab")
		)
		(fp_line
			(start 0.3048 -0.1016)
			(end 0.3048 0.9906)
			(stroke
				(width 0.1)
				(type default)
			)
			(layer "B.Fab")
		)
		(fp_line
			(start 0.3048 0.9906)
			(end -0.3048 0.9906)
			(stroke
				(width 0.1)
				(type default)
			)
			(layer "B.Fab")
		)
		(pad "1" smd rect
			(at 0 0 180)
			(size 0.508 0.508)
			(layers "B.Cu" "B.Mask" "B.Paste")
			(net "P12V_STBY")
		)
		(pad "2" smd rect
			(at 0 0.889 180)
			(size 0.508 0.508)
			(layers "B.Cu" "B.Mask" "B.Paste")
			(net "GND")
		)
		(zone
			(layer "B.Cu")
			(hatch none 0.5)
			(connect_pads
				(clearance 0)
			)
			(min_thickness 0.25)
			(keepout
				(tracks allowed)
				(vias not_allowed)
				(pads allowed)
				(copperpour not_allowed)
				(footprints allowed)
			)
			(placement
				(enabled no)
				(sheetname "")
			)
			(fill
				(thermal_gap 0.5)
				(thermal_bridge_width 0.5)
				(island_removal_mode 0)
			)
			(polygon
				(pts
					(xy 439.547 -52.1335) (xy 439.039 -52.1335) (xy 439.039 -51.7525) (xy 439.547 -51.7525)
				)
			)
		)
		(zone
			(layer "B.Cu")
			(hatch none 0.5)
			(connect_pads
				(clearance 0)
			)
			(min_thickness 0.25)
			(keepout
				(tracks not_allowed)
				(vias allowed)
				(pads allowed)
				(copperpour not_allowed)
				(footprints allowed)
			)
			(placement
				(enabled no)
				(sheetname "")
			)
			(fill
				(thermal_gap 0.5)
				(thermal_bridge_width 0.5)
				(island_removal_mode 0)
			)
			(polygon
				(pts
					(xy 439.547 -51.7525) (xy 439.039 -51.7525) (xy 439.039 -52.1335) (xy 439.547 -52.1335)
				)
			)
		)
	)
	(footprint ""
		(layer "B.Cu")
		(at 421.956992 -77.523594 180)
		(property "Reference" "R1R8"
			(at 0 0 0)
			(layer "B.SilkS")
			(hide yes)
			(effects
				(font
					(size 1.27 1.27)
				)
				(justify mirror)
			)
		)
		(property "Value" ""
			(at 0 0 0)
			(layer "B.Fab")
			(effects
				(font
					(size 1.27 1.27)
				)
				(justify mirror)
			)
		)
		(duplicate_pad_numbers_are_jumpers no)
		(fp_poly
			(pts
				(xy 0.2794 -0.1016) (xy -0.2794 -0.1016) (xy -0.2794 0.9906) (xy 0.2794 0.9906)
			)
			(stroke
				(width 0)
				(type default)
			)
			(fill no)
			(layer "B.CrtYd")
		)
		(fp_line
			(start 0.2794 0.9906)
			(end -0.2794 0.9906)
			(stroke
				(width 0.1)
				(type default)
			)
			(layer "B.Fab")
		)
		(fp_line
			(start 0.2794 -0.1016)
			(end 0.2794 0.9906)
			(stroke
				(width 0.1)
				(type default)
			)
			(layer "B.Fab")
		)
		(fp_line
			(start -0.2794 0.9906)
			(end -0.2794 -0.1016)
			(stroke
				(width 0.1)
				(type default)
			)
			(layer "B.Fab")
		)
		(fp_line
			(start -0.2794 -0.1016)
			(end 0.2794 -0.1016)
			(stroke
				(width 0.1)
				(type default)
			)
			(layer "B.Fab")
		)
		(pad "1" smd rect
			(at 0 0)
			(size 0.508 0.508)
			(layers "B.Cu" "B.Mask" "B.Paste")
			(net "FM_THROTTLE_R1_N")
		)
		(pad "2" smd rect
			(at 0 0.889)
			(size 0.508 0.508)
			(layers "B.Cu" "B.Mask" "B.Paste")
			(net "FM_THROTTLE_N")
		)
		(zone
			(layer "B.Cu")
			(hatch none 0.5)
			(connect_pads
				(clearance 0)
			)
			(min_thickness 0.25)
			(keepout
				(tracks not_allowed)
				(vias allowed)
				(pads allowed)
				(copperpour not_allowed)
				(footprints allowed)
			)
			(placement
				(enabled no)
				(sheetname "")
			)
			(fill
				(thermal_gap 0.5)
				(thermal_bridge_width 0.5)
				(island_removal_mode 0)
			)
			(polygon
				(pts
					(xy 421.702992 -78.158594) (xy 422.210992 -78.158594) (xy 422.210992 -77.777594) (xy 421.702992 -77.777594)
				)
			)
		)
		(zone
			(layer "B.Cu")
			(hatch none 0.5)
			(connect_pads
				(clearance 0)
			)
			(min_thickness 0.25)
			(keepout
				(tracks allowed)
				(vias not_allowed)
				(pads allowed)
				(copperpour not_allowed)
				(footprints allowed)
			)
			(placement
				(enabled no)
				(sheetname "")
			)
			(fill
				(thermal_gap 0.5)
				(thermal_bridge_width 0.5)
				(island_removal_mode 0)
			)
			(polygon
				(pts
					(xy 421.702992 -77.777594) (xy 422.210992 -77.777594) (xy 422.210992 -78.158594) (xy 421.702992 -78.158594)
				)
			)
		)
	)
)
